# S9S_MB_2U (Grand Teton) — schematic netlist excerpt (pin names and nets, part order shuffled) for the footprints in the layout excerpt that follows; sources: Cadence DE-HDL packaged netlist, KiCad conversion of 03242023_DA0F0TMBIJ0_F0T_Motherboard_J_brd_V01_OCP.brd

PR3949  Q_RES  56K 1% CHIP  pkg 0402LF  page 193 : A = P12V_E1S_IMON_0 ; B = GND
R3669  Q_RES  1K 1% EMPTY  pkg 0402LF  page 250 : A = P3V3_AUX ; B = ADC128_A0

(kicad_pcb
	(version 20260206)
	(generator "pcbnew")
	(generator_version "10.0")
	(general
		(thickness 1.6)
		(legacy_teardrops no)
	)
	(paper "A4")
	(title_block
		(title "03242023_DA0F0TMBIJ0_F0T_Motherboard_J_brd_V01_OCP.brd")
		(comment 1 "Grand Teton / footprints 1746-1747 of 6105")
	)
	(layers
		(0 "F.Cu" signal "TOP")
		(4 "In1.Cu" signal "GND")
		(6 "In2.Cu" signal "IN1")
		(8 "In3.Cu" signal "GND1")
		(10 "In4.Cu" signal "IN2")
		(12 "In5.Cu" signal "GND2")
		(14 "In6.Cu" signal "IN3")
		(16 "In7.Cu" signal "GND3")
		(18 "In8.Cu" signal "VCC")
		(20 "In9.Cu" signal "VCC1")
		(22 "In10.Cu" signal "GND4")
		(24 "In11.Cu" signal "IN4")
		(26 "In12.Cu" signal "GND5")
		(28 "In13.Cu" signal "IN5")
		(30 "In14.Cu" signal "GND6")
		(32 "In15.Cu" signal "IN6")
		(34 "In16.Cu" signal "GND7")
		(2 "B.Cu" signal "BOTTOM")
		(9 "F.Adhes" user "F.Adhesive")
		(11 "B.Adhes" user "B.Adhesive")
		(13 "F.Paste" user "Package Geometry/Pastemask Top")
		(15 "B.Paste" user "Package Geometry/Pastemask Bottom")
		(5 "F.SilkS" user "Ref Des/Silkscreen Top")
		(7 "B.SilkS" user "Ref Des/Silkscreen Bottom")
		(1 "F.Mask" user "Board Geometry/Soldermask Top")
		(3 "B.Mask" user "Board Geometry/Soldermask Bottom")
		(17 "Dwgs.User" user "User.Drawings")
		(19 "Cmts.User" user "User.Comments")
		(21 "Eco1.User" user "User.Eco1")
		(23 "Eco2.User" user "User.Eco2")
		(25 "Edge.Cuts" user "Board Geometry/Outline")
		(27 "Margin" user)
		(31 "F.CrtYd" user "Package Geometry/Place Bound Top")
		(29 "B.CrtYd" user "Package Geometry/Place Bound Bottom")
		(35 "F.Fab" user "Ref Des/Assembly Top")
		(33 "B.Fab" user "Ref Des/Assembly Bottom")
	)
	(footprint ""
		(layer "F.Cu")
		(at 20.190714 -107.777026)
		(property "Reference" "R3669"
			(at 0 0 0)
			(layer "F.SilkS")
			(hide yes)
			(effects
				(font
					(size 1.27 1.27)
				)
			)
		)
		(property "Value" ""
			(at 0 0 0)
			(layer "F.Fab")
			(effects
				(font
					(size 1.27 1.27)
				)
			)
		)
		(duplicate_pad_numbers_are_jumpers no)
		(fp_line
			(start -0.7874 -0.4064)
			(end 0.7874 -0.4064)
			(stroke
				(width 0.1524)
				(type default)
			)
			(layer "F.SilkS")
		)
		(fp_line
			(start -0.7874 0.4064)
			(end -0.7874 -0.4064)
			(stroke
				(width 0.1524)
				(type default)
			)
			(layer "F.SilkS")
		)
		(fp_line
			(start 0.7874 -0.4064)
			(end 0.7874 0.4064)
			(stroke
				(width 0.1524)
				(type default)
			)
			(layer "F.SilkS")
		)
		(fp_line
			(start 0.7874 0.4064)
			(end -0.7874 0.4064)
			(stroke
				(width 0.1524)
				(type default)
			)
			(layer "F.SilkS")
		)
		(fp_line
			(start -0.67945 -0.305054)
			(end -0.12065 -0.305054)
			(stroke
				(width 0.1)
				(type default)
			)
			(layer "F.Fab")
		)
		(fp_line
			(start -0.67945 0.3048)
			(end -0.67945 -0.305054)
			(stroke
				(width 0.1)
				(type default)
			)
			(layer "F.Fab")
		)
		(fp_line
			(start -0.12065 -0.305054)
			(end -0.12065 -0.2794)
			(stroke
				(width 0.1)
				(type default)
			)
			(layer "F.Fab")
		)
		(fp_line
			(start -0.12065 -0.2794)
			(end 0.12065 -0.2794)
			(stroke
				(width 0.1)
				(type default)
			)
			(layer "F.Fab")
		)
		(fp_line
			(start -0.12065 0.2794)
			(end -0.12065 0.3048)
			(stroke
				(width 0.1)
				(type default)
			)
			(layer "F.Fab")
		)
		(fp_line
			(start -0.12065 0.3048)
			(end -0.67945 0.3048)
			(stroke
				(width 0.1)
				(type default)
			)
			(layer "F.Fab")
		)
		(fp_line
			(start 0.120396 0.2794)
			(end -0.12065 0.2794)
			(stroke
				(width 0.1)
				(type default)
			)
			(layer "F.Fab")
		)
		(fp_line
			(start 0.120396 0.3048)
			(end 0.120396 0.2794)
			(stroke
				(width 0.1)
				(type default)
			)
			(layer "F.Fab")
		)
		(fp_line
			(start 0.12065 -0.3048)
			(end 0.67945 -0.3048)
			(stroke
				(width 0.1)
				(type default)
			)
			(layer "F.Fab")
		)
		(fp_line
			(start 0.12065 -0.2794)
			(end 0.12065 -0.3048)
			(stroke
				(width 0.1)
				(type default)
			)
			(layer "F.Fab")
		)
		(fp_line
			(start 0.67945 -0.3048)
			(end 0.67945 0.3048)
			(stroke
				(width 0.1)
				(type default)
			)
			(layer "F.Fab")
		)
		(fp_line
			(start 0.67945 0.3048)
			(end 0.120396 0.3048)
			(stroke
				(width 0.1)
				(type default)
			)
			(layer "F.Fab")
		)
		(pad "1" smd circle
			(at -0.40005 0)
			(size 0 0)
			(layers "F.Cu" "F.Mask" "F.Paste")
			(net "P3V3_AUX")
		)
		(pad "2" smd circle
			(at 0.40005 0)
			(size 0 0)
			(layers "F.Cu" "F.Mask" "F.Paste")
			(net "ADC128_A0")
		)
	)
	(footprint ""
		(layer "F.Cu")
		(at 257.85953 -54.463442)
		(property "Reference" "PR3949"
			(at 0 0 0)
			(layer "F.SilkS")
			(hide yes)
			(effects
				(font
					(size 1.27 1.27)
				)
			)
		)
		(property "Value" ""
			(at 0 0 0)
			(layer "F.Fab")
			(effects
				(font
					(size 1.27 1.27)
				)
			)
		)
		(duplicate_pad_numbers_are_jumpers no)
		(fp_line
			(start -0.7874 -0.4064)
			(end 0.7874 -0.4064)
			(stroke
				(width 0.1524)
				(type default)
			)
			(layer "F.SilkS")
		)
		(fp_line
			(start -0.7874 0.4064)
			(end -0.7874 -0.4064)
			(stroke
				(width 0.1524)
				(type default)
			)
			(layer "F.SilkS")
		)
		(fp_line
			(start 0.7874 -0.4064)
			(end 0.7874 0.4064)
			(stroke
				(width 0.1524)
				(type default)
			)
			(layer "F.SilkS")
		)
		(fp_line
			(start 0.7874 0.4064)
			(end -0.7874 0.4064)
			(stroke
				(width 0.1524)
				(type default)
			)
			(layer "F.SilkS")
		)
		(fp_line
			(start -0.67945 -0.305054)
			(end -0.12065 -0.305054)
			(stroke
				(width 0.1)
				(type default)
			)
			(layer "F.Fab")
		)
		(fp_line
			(start -0.67945 0.3048)
			(end -0.67945 -0.305054)
			(stroke
				(width 0.1)
				(type default)
			)
			(layer "F.Fab")
		)
		(fp_line
			(start -0.12065 -0.305054)
			(end -0.12065 -0.2794)
			(stroke
				(width 0.1)
				(type default)
			)
			(layer "F.Fab")
		)
		(fp_line
			(start -0.12065 -0.2794)
			(end 0.12065 -0.2794)
			(stroke
				(width 0.1)
				(type default)
			)
			(layer "F.Fab")
		)
		(fp_line
			(start -0.12065 0.2794)
			(end -0.12065 0.3048)
			(stroke
				(width 0.1)
				(type default)
			)
			(layer "F.Fab")
		)
		(fp_line
			(start -0.12065 0.3048)
			(end -0.67945 0.3048)
			(stroke
				(width 0.1)
				(type default)
			)
			(layer "F.Fab")
		)
		(fp_line
			(start 0.120396 0.2794)
			(end -0.12065 0.2794)
			(stroke
				(width 0.1)
				(type default)
			)
			(layer "F.Fab")
		)
		(fp_line
			(start 0.120396 0.3048)
			(end 0.120396 0.2794)
			(stroke
				(width 0.1)
				(type default)
			)
			(layer "F.Fab")
		)
		(fp_line
			(start 0.12065 -0.3048)
			(end 0.67945 -0.3048)
			(stroke
				(width 0.1)
				(type default)
			)
			(layer "F.Fab")
		)
		(fp_line
			(start 0.12065 -0.2794)
			(end 0.12065 -0.3048)
			(stroke
				(width 0.1)
				(type default)
			)
			(layer "F.Fab")
		)
		(fp_line
			(start 0.67945 -0.3048)
			(end 0.67945 0.3048)
			(stroke
				(width 0.1)
				(type default)
			)
			(layer "F.Fab")
		)
		(fp_line
			(start 0.67945 0.3048)
			(end 0.120396 0.3048)
			(stroke
				(width 0.1)
				(type default)
			)
			(layer "F.Fab")
		)
		(pad "1" smd circle
			(at -0.40005 0)
			(size 0 0)
			(layers "F.Cu" "F.Mask" "F.Paste")
			(net "P12V_E1S_IMON_0")
		)
		(pad "2" smd circle
			(at 0.40005 0)
			(size 0 0)
			(layers "F.Cu" "F.Mask" "F.Paste")
			(net "GND")
		)
	)
)
